# S9S_MB_2U (Grand Teton) — schematic netlist excerpt (pin names and nets, part order shuffled) for the footprints in the layout excerpt that follows; sources: Cadence DE-HDL packaged netlist, KiCad conversion of 03242023_DA0F0TMBIJ0_F0T_Motherboard_J_brd_V01_OCP.brd

R3130  Q_RES  10K 1% CHIP  pkg 0402LF  page 236 : A = P3V3_AUX ; B = PCA9543_S3M_INT2_N
R2660  Q_RES  0 5% CHIP  pkg 0402LF  page 207 : A = CLK_100M_SWB_R_DN ; B = CLK_100M_SWB_DN
C760  Q_CAP_DIFFBUS  DIFF BUS_0.22UF 6.3V 20% X6S  pkg C0201  page 176 : \1\ = P5E_CPU1_PE2_TX_C_DN<6> ; \2\ = P5E_CPU1_PE2_TX_DN<6>

(kicad_pcb
	(version 20260206)
	(generator "pcbnew")
	(generator_version "10.0")
	(general
		(thickness 1.6)
		(legacy_teardrops no)
	)
	(paper "A4")
	(title_block
		(title "03242023_DA0F0TMBIJ0_F0T_Motherboard_J_brd_V01_OCP.brd")
		(comment 1 "Grand Teton / footprints 2780-2782 of 6105")
	)
	(layers
		(0 "F.Cu" signal "TOP")
		(4 "In1.Cu" signal "GND")
		(6 "In2.Cu" signal "IN1")
		(8 "In3.Cu" signal "GND1")
		(10 "In4.Cu" signal "IN2")
		(12 "In5.Cu" signal "GND2")
		(14 "In6.Cu" signal "IN3")
		(16 "In7.Cu" signal "GND3")
		(18 "In8.Cu" signal "VCC")
		(20 "In9.Cu" signal "VCC1")
		(22 "In10.Cu" signal "GND4")
		(24 "In11.Cu" signal "IN4")
		(26 "In12.Cu" signal "GND5")
		(28 "In13.Cu" signal "IN5")
		(30 "In14.Cu" signal "GND6")
		(32 "In15.Cu" signal "IN6")
		(34 "In16.Cu" signal "GND7")
		(2 "B.Cu" signal "BOTTOM")
		(9 "F.Adhes" user "F.Adhesive")
		(11 "B.Adhes" user "B.Adhesive")
		(13 "F.Paste" user "Package Geometry/Pastemask Top")
		(15 "B.Paste" user "Package Geometry/Pastemask Bottom")
		(5 "F.SilkS" user "Ref Des/Silkscreen Top")
		(7 "B.SilkS" user "Ref Des/Silkscreen Bottom")
		(1 "F.Mask" user "Board Geometry/Soldermask Top")
		(3 "B.Mask" user "Board Geometry/Soldermask Bottom")
		(17 "Dwgs.User" user "User.Drawings")
		(19 "Cmts.User" user "User.Comments")
		(21 "Eco1.User" user "User.Eco1")
		(23 "Eco2.User" user "User.Eco2")
		(25 "Edge.Cuts" user "Board Geometry/Outline")
		(27 "Margin" user)
		(31 "F.CrtYd" user "Package Geometry/Place Bound Top")
		(29 "B.CrtYd" user "Package Geometry/Place Bound Bottom")
		(35 "F.Fab" user "Ref Des/Assembly Top")
		(33 "B.Fab" user "Ref Des/Assembly Bottom")
	)
	(footprint ""
		(layer "F.Cu")
		(at 111.24946 -418.027358 90)
		(property "Reference" "R2660"
			(at 0 0 90)
			(layer "F.SilkS")
			(hide yes)
			(effects
				(font
					(size 1.27 1.27)
				)
			)
		)
		(property "Value" ""
			(at 0 0 90)
			(layer "F.Fab")
			(effects
				(font
					(size 1.27 1.27)
				)
			)
		)
		(duplicate_pad_numbers_are_jumpers no)
		(fp_line
			(start 0.7874 -0.4064)
			(end 0.7874 0.03556)
			(stroke
				(width 0.1524)
				(type default)
			)
			(layer "F.SilkS")
		)
		(fp_line
			(start -0.7874 -0.4064)
			(end 0.7874 -0.4064)
			(stroke
				(width 0.1524)
				(type default)
			)
			(layer "F.SilkS")
		)
		(fp_line
			(start -0.7874 -0.0127)
			(end -0.7874 -0.4064)
			(stroke
				(width 0.1524)
				(type default)
			)
			(layer "F.SilkS")
		)
		(fp_line
			(start 0.35941 0.4064)
			(end -0.39751 0.4064)
			(stroke
				(width 0.1524)
				(type default)
			)
			(layer "F.SilkS")
		)
		(fp_line
			(start -0.12065 -0.305054)
			(end -0.12065 -0.2794)
			(stroke
				(width 0.1)
				(type default)
			)
			(layer "F.Fab")
		)
		(fp_line
			(start -0.67945 -0.305054)
			(end -0.12065 -0.305054)
			(stroke
				(width 0.1)
				(type default)
			)
			(layer "F.Fab")
		)
		(fp_line
			(start 0.67945 -0.3048)
			(end 0.67945 0.3048)
			(stroke
				(width 0.1)
				(type default)
			)
			(layer "F.Fab")
		)
		(fp_line
			(start 0.12065 -0.3048)
			(end 0.67945 -0.3048)
			(stroke
				(width 0.1)
				(type default)
			)
			(layer "F.Fab")
		)
		(fp_line
			(start 0.12065 -0.2794)
			(end 0.12065 -0.3048)
			(stroke
				(width 0.1)
				(type default)
			)
			(layer "F.Fab")
		)
		(fp_line
			(start -0.12065 -0.2794)
			(end 0.12065 -0.2794)
			(stroke
				(width 0.1)
				(type default)
			)
			(layer "F.Fab")
		)
		(fp_line
			(start 0.120396 0.2794)
			(end -0.12065 0.2794)
			(stroke
				(width 0.1)
				(type default)
			)
			(layer "F.Fab")
		)
		(fp_line
			(start -0.12065 0.2794)
			(end -0.12065 0.3048)
			(stroke
				(width 0.1)
				(type default)
			)
			(layer "F.Fab")
		)
		(fp_line
			(start 0.67945 0.3048)
			(end 0.120396 0.3048)
			(stroke
				(width 0.1)
				(type default)
			)
			(layer "F.Fab")
		)
		(fp_line
			(start 0.120396 0.3048)
			(end 0.120396 0.2794)
			(stroke
				(width 0.1)
				(type default)
			)
			(layer "F.Fab")
		)
		(fp_line
			(start -0.12065 0.3048)
			(end -0.67945 0.3048)
			(stroke
				(width 0.1)
				(type default)
			)
			(layer "F.Fab")
		)
		(fp_line
			(start -0.67945 0.3048)
			(end -0.67945 -0.305054)
			(stroke
				(width 0.1)
				(type default)
			)
			(layer "F.Fab")
		)
		(pad "1" smd circle
			(at -0.40005 0 90)
			(size 0 0)
			(layers "F.Cu" "F.Mask" "F.Paste")
			(net "CLK_100M_SWB_R_DN")
		)
		(pad "2" smd circle
			(at 0.40005 0 90)
			(size 0 0)
			(layers "F.Cu" "F.Mask" "F.Paste")
			(net "CLK_100M_SWB_DN")
		)
	)
	(footprint ""
		(layer "F.Cu")
		(at 148.98243 -79.139034)
		(property "Reference" "R3130"
			(at 0 0 0)
			(layer "F.SilkS")
			(hide yes)
			(effects
				(font
					(size 1.27 1.27)
				)
			)
		)
		(property "Value" ""
			(at 0 0 0)
			(layer "F.Fab")
			(effects
				(font
					(size 1.27 1.27)
				)
			)
		)
		(duplicate_pad_numbers_are_jumpers no)
		(fp_line
			(start -0.7874 -0.4064)
			(end 0.7874 -0.4064)
			(stroke
				(width 0.1524)
				(type default)
			)
			(layer "F.SilkS")
		)
		(fp_line
			(start -0.7874 0.4064)
			(end -0.7874 -0.4064)
			(stroke
				(width 0.1524)
				(type default)
			)
			(layer "F.SilkS")
		)
		(fp_line
			(start 0.7874 -0.4064)
			(end 0.7874 0.4064)
			(stroke
				(width 0.1524)
				(type default)
			)
			(layer "F.SilkS")
		)
		(fp_line
			(start 0.7874 0.4064)
			(end -0.7874 0.4064)
			(stroke
				(width 0.1524)
				(type default)
			)
			(layer "F.SilkS")
		)
		(fp_line
			(start -0.67945 -0.305054)
			(end -0.12065 -0.305054)
			(stroke
				(width 0.1)
				(type default)
			)
			(layer "F.Fab")
		)
		(fp_line
			(start -0.67945 0.3048)
			(end -0.67945 -0.305054)
			(stroke
				(width 0.1)
				(type default)
			)
			(layer "F.Fab")
		)
		(fp_line
			(start -0.12065 -0.305054)
			(end -0.12065 -0.2794)
			(stroke
				(width 0.1)
				(type default)
			)
			(layer "F.Fab")
		)
		(fp_line
			(start -0.12065 -0.2794)
			(end 0.12065 -0.2794)
			(stroke
				(width 0.1)
				(type default)
			)
			(layer "F.Fab")
		)
		(fp_line
			(start -0.12065 0.2794)
			(end -0.12065 0.3048)
			(stroke
				(width 0.1)
				(type default)
			)
			(layer "F.Fab")
		)
		(fp_line
			(start -0.12065 0.3048)
			(end -0.67945 0.3048)
			(stroke
				(width 0.1)
				(type default)
			)
			(layer "F.Fab")
		)
		(fp_line
			(start 0.120396 0.2794)
			(end -0.12065 0.2794)
			(stroke
				(width 0.1)
				(type default)
			)
			(layer "F.Fab")
		)
		(fp_line
			(start 0.120396 0.3048)
			(end 0.120396 0.2794)
			(stroke
				(width 0.1)
				(type default)
			)
			(layer "F.Fab")
		)
		(fp_line
			(start 0.12065 -0.3048)
			(end 0.67945 -0.3048)
			(stroke
				(width 0.1)
				(type default)
			)
			(layer "F.Fab")
		)
		(fp_line
			(start 0.12065 -0.2794)
			(end 0.12065 -0.3048)
			(stroke
				(width 0.1)
				(type default)
			)
			(layer "F.Fab")
		)
		(fp_line
			(start 0.67945 -0.3048)
			(end 0.67945 0.3048)
			(stroke
				(width 0.1)
				(type default)
			)
			(layer "F.Fab")
		)
		(fp_line
			(start 0.67945 0.3048)
			(end 0.120396 0.3048)
			(stroke
				(width 0.1)
				(type default)
			)
			(layer "F.Fab")
		)
		(pad "1" smd circle
			(at -0.40005 0)
			(size 0 0)
			(layers "F.Cu" "F.Mask" "F.Paste")
			(net "P3V3_AUX")
		)
		(pad "2" smd circle
			(at 0.40005 0)
			(size 0 0)
			(layers "F.Cu" "F.Mask" "F.Paste")
			(net "PCA9543_S3M_INT2_N")
		)
	)
	(footprint ""
		(layer "F.Cu")
		(at 148.613114 -402.371052 -90)
		(property "Reference" "C760"
			(at 0 0 270)
			(layer "F.SilkS")
			(hide yes)
			(effects
				(font
					(size 1.27 1.27)
				)
			)
		)
		(property "Value" ""
			(at 0 0 270)
			(layer "F.Fab")
			(effects
				(font
					(size 1.27 1.27)
				)
			)
		)
		(duplicate_pad_numbers_are_jumpers no)
		(fp_line
			(start -0.299974 0.150114)
			(end -0.299974 -0.150114)
			(stroke
				(width 0.1)
				(type default)
			)
			(layer "F.Fab")
		)
		(fp_line
			(start 0.299974 0.150114)
			(end -0.299974 0.150114)
			(stroke
				(width 0.1)
				(type default)
			)
			(layer "F.Fab")
		)
		(fp_line
			(start -0.299974 -0.150114)
			(end 0.299974 -0.150114)
			(stroke
				(width 0.1)
				(type default)
			)
			(layer "F.Fab")
		)
		(fp_line
			(start 0.299974 -0.150114)
			(end 0.299974 0.150114)
			(stroke
				(width 0.1)
				(type default)
			)
			(layer "F.Fab")
		)
		(pad "1" smd rect
			(at -0.2667 0 270)
			(size 0.3048 0.381)
			(layers "F.Cu" "F.Mask" "F.Paste")
			(net "P5E_CPU1_PE2_TX_C_DN<6>")
		)
		(pad "2" smd rect
			(at 0.2667 0 270)
			(size 0.3048 0.381)
			(layers "F.Cu" "F.Mask" "F.Paste")
			(net "P5E_CPU1_PE2_TX_DN<6>")
		)
	)
)
